# S9S_MB_2U (Grand Teton) — schematic netlist excerpt (pin names and nets, part order shuffled) for the footprints in the layout excerpt that follows; sources: Cadence DE-HDL packaged netlist, KiCad conversion of 03242023_DA0F0TMBIJ0_F0T_Motherboard_J_brd_V01_OCP.brd

R369  Q_RES  1K 1% CHIP  pkg 0402LF  page 198 : A = P3V3_AUX ; B = FM_ADR_ACK
R1514  Q_RES  33.2 1% CHIP  pkg 0402LF  page 223 : A = RST_PCIE_CPU0_DEV_PERST_N ; B = RST_OCP_V3_1_N

(kicad_pcb
	(version 20260206)
	(generator "pcbnew")
	(generator_version "10.0")
	(general
		(thickness 1.6)
		(legacy_teardrops no)
	)
	(paper "A4")
	(title_block
		(title "03242023_DA0F0TMBIJ0_F0T_Motherboard_J_brd_V01_OCP.brd")
		(comment 1 "Grand Teton / footprints 2510-2511 of 6105")
	)
	(layers
		(0 "F.Cu" signal "TOP")
		(4 "In1.Cu" signal "GND")
		(6 "In2.Cu" signal "IN1")
		(8 "In3.Cu" signal "GND1")
		(10 "In4.Cu" signal "IN2")
		(12 "In5.Cu" signal "GND2")
		(14 "In6.Cu" signal "IN3")
		(16 "In7.Cu" signal "GND3")
		(18 "In8.Cu" signal "VCC")
		(20 "In9.Cu" signal "VCC1")
		(22 "In10.Cu" signal "GND4")
		(24 "In11.Cu" signal "IN4")
		(26 "In12.Cu" signal "GND5")
		(28 "In13.Cu" signal "IN5")
		(30 "In14.Cu" signal "GND6")
		(32 "In15.Cu" signal "IN6")
		(34 "In16.Cu" signal "GND7")
		(2 "B.Cu" signal "BOTTOM")
		(9 "F.Adhes" user "F.Adhesive")
		(11 "B.Adhes" user "B.Adhesive")
		(13 "F.Paste" user "Package Geometry/Pastemask Top")
		(15 "B.Paste" user "Package Geometry/Pastemask Bottom")
		(5 "F.SilkS" user "Ref Des/Silkscreen Top")
		(7 "B.SilkS" user "Ref Des/Silkscreen Bottom")
		(1 "F.Mask" user "Board Geometry/Soldermask Top")
		(3 "B.Mask" user "Board Geometry/Soldermask Bottom")
		(17 "Dwgs.User" user "User.Drawings")
		(19 "Cmts.User" user "User.Comments")
		(21 "Eco1.User" user "User.Eco1")
		(23 "Eco2.User" user "User.Eco2")
		(25 "Edge.Cuts" user "Board Geometry/Outline")
		(27 "Margin" user)
		(31 "F.CrtYd" user "Package Geometry/Place Bound Top")
		(29 "B.CrtYd" user "Package Geometry/Place Bound Bottom")
		(35 "F.Fab" user "Ref Des/Assembly Top")
		(33 "B.Fab" user "Ref Des/Assembly Bottom")
	)
	(footprint ""
		(layer "F.Cu")
		(at 197.41388 -99.875848 180)
		(property "Reference" "R369"
			(at 0 0 180)
			(layer "F.SilkS")
			(hide yes)
			(effects
				(font
					(size 1.27 1.27)
				)
			)
		)
		(property "Value" ""
			(at 0 0 180)
			(layer "F.Fab")
			(effects
				(font
					(size 1.27 1.27)
				)
			)
		)
		(duplicate_pad_numbers_are_jumpers no)
		(fp_line
			(start 0.7874 0.4064)
			(end -0.7874 0.4064)
			(stroke
				(width 0.1524)
				(type default)
			)
			(layer "F.SilkS")
		)
		(fp_line
			(start 0.7874 -0.4064)
			(end 0.7874 0.4064)
			(stroke
				(width 0.1524)
				(type default)
			)
			(layer "F.SilkS")
		)
		(fp_line
			(start -0.7874 0.4064)
			(end -0.7874 -0.4064)
			(stroke
				(width 0.1524)
				(type default)
			)
			(layer "F.SilkS")
		)
		(fp_line
			(start -0.7874 -0.4064)
			(end 0.7874 -0.4064)
			(stroke
				(width 0.1524)
				(type default)
			)
			(layer "F.SilkS")
		)
		(fp_line
			(start 0.67945 0.3048)
			(end 0.120396 0.3048)
			(stroke
				(width 0.1)
				(type default)
			)
			(layer "F.Fab")
		)
		(fp_line
			(start 0.67945 -0.3048)
			(end 0.67945 0.3048)
			(stroke
				(width 0.1)
				(type default)
			)
			(layer "F.Fab")
		)
		(fp_line
			(start 0.12065 -0.2794)
			(end 0.12065 -0.3048)
			(stroke
				(width 0.1)
				(type default)
			)
			(layer "F.Fab")
		)
		(fp_line
			(start 0.12065 -0.3048)
			(end 0.67945 -0.3048)
			(stroke
				(width 0.1)
				(type default)
			)
			(layer "F.Fab")
		)
		(fp_line
			(start 0.120396 0.3048)
			(end 0.120396 0.2794)
			(stroke
				(width 0.1)
				(type default)
			)
			(layer "F.Fab")
		)
		(fp_line
			(start 0.120396 0.2794)
			(end -0.12065 0.2794)
			(stroke
				(width 0.1)
				(type default)
			)
			(layer "F.Fab")
		)
		(fp_line
			(start -0.12065 0.3048)
			(end -0.67945 0.3048)
			(stroke
				(width 0.1)
				(type default)
			)
			(layer "F.Fab")
		)
		(fp_line
			(start -0.12065 0.2794)
			(end -0.12065 0.3048)
			(stroke
				(width 0.1)
				(type default)
			)
			(layer "F.Fab")
		)
		(fp_line
			(start -0.12065 -0.2794)
			(end 0.12065 -0.2794)
			(stroke
				(width 0.1)
				(type default)
			)
			(layer "F.Fab")
		)
		(fp_line
			(start -0.12065 -0.305054)
			(end -0.12065 -0.2794)
			(stroke
				(width 0.1)
				(type default)
			)
			(layer "F.Fab")
		)
		(fp_line
			(start -0.67945 0.3048)
			(end -0.67945 -0.305054)
			(stroke
				(width 0.1)
				(type default)
			)
			(layer "F.Fab")
		)
		(fp_line
			(start -0.67945 -0.305054)
			(end -0.12065 -0.305054)
			(stroke
				(width 0.1)
				(type default)
			)
			(layer "F.Fab")
		)
		(pad "1" smd circle
			(at -0.40005 0 180)
			(size 0 0)
			(layers "F.Cu" "F.Mask" "F.Paste")
			(net "P3V3_AUX")
		)
		(pad "2" smd circle
			(at 0.40005 0 180)
			(size 0 0)
			(layers "F.Cu" "F.Mask" "F.Paste")
			(net "FM_ADR_ACK")
		)
	)
	(footprint ""
		(layer "F.Cu")
		(at 393.290552 -32.456374 180)
		(property "Reference" "R1514"
			(at 0 0 180)
			(layer "F.SilkS")
			(hide yes)
			(effects
				(font
					(size 1.27 1.27)
				)
			)
		)
		(property "Value" ""
			(at 0 0 180)
			(layer "F.Fab")
			(effects
				(font
					(size 1.27 1.27)
				)
			)
		)
		(duplicate_pad_numbers_are_jumpers no)
		(fp_line
			(start 0.7874 0.4064)
			(end -0.7874 0.4064)
			(stroke
				(width 0.1524)
				(type default)
			)
			(layer "F.SilkS")
		)
		(fp_line
			(start 0.7874 -0.4064)
			(end 0.7874 0.4064)
			(stroke
				(width 0.1524)
				(type default)
			)
			(layer "F.SilkS")
		)
		(fp_line
			(start -0.7874 0.4064)
			(end -0.7874 -0.4064)
			(stroke
				(width 0.1524)
				(type default)
			)
			(layer "F.SilkS")
		)
		(fp_line
			(start -0.7874 -0.4064)
			(end 0.7874 -0.4064)
			(stroke
				(width 0.1524)
				(type default)
			)
			(layer "F.SilkS")
		)
		(fp_line
			(start 0.67945 0.3048)
			(end 0.120396 0.3048)
			(stroke
				(width 0.1)
				(type default)
			)
			(layer "F.Fab")
		)
		(fp_line
			(start 0.67945 -0.3048)
			(end 0.67945 0.3048)
			(stroke
				(width 0.1)
				(type default)
			)
			(layer "F.Fab")
		)
		(fp_line
			(start 0.12065 -0.2794)
			(end 0.12065 -0.3048)
			(stroke
				(width 0.1)
				(type default)
			)
			(layer "F.Fab")
		)
		(fp_line
			(start 0.12065 -0.3048)
			(end 0.67945 -0.3048)
			(stroke
				(width 0.1)
				(type default)
			)
			(layer "F.Fab")
		)
		(fp_line
			(start 0.120396 0.3048)
			(end 0.120396 0.2794)
			(stroke
				(width 0.1)
				(type default)
			)
			(layer "F.Fab")
		)
		(fp_line
			(start 0.120396 0.2794)
			(end -0.12065 0.2794)
			(stroke
				(width 0.1)
				(type default)
			)
			(layer "F.Fab")
		)
		(fp_line
			(start -0.12065 0.3048)
			(end -0.67945 0.3048)
			(stroke
				(width 0.1)
				(type default)
			)
			(layer "F.Fab")
		)
		(fp_line
			(start -0.12065 0.2794)
			(end -0.12065 0.3048)
			(stroke
				(width 0.1)
				(type default)
			)
			(layer "F.Fab")
		)
		(fp_line
			(start -0.12065 -0.2794)
			(end 0.12065 -0.2794)
			(stroke
				(width 0.1)
				(type default)
			)
			(layer "F.Fab")
		)
		(fp_line
			(start -0.12065 -0.305054)
			(end -0.12065 -0.2794)
			(stroke
				(width 0.1)
				(type default)
			)
			(layer "F.Fab")
		)
		(fp_line
			(start -0.67945 0.3048)
			(end -0.67945 -0.305054)
			(stroke
				(width 0.1)
				(type default)
			)
			(layer "F.Fab")
		)
		(fp_line
			(start -0.67945 -0.305054)
			(end -0.12065 -0.305054)
			(stroke
				(width 0.1)
				(type default)
			)
			(layer "F.Fab")
		)
		(pad "1" smd circle
			(at -0.40005 0 180)
			(size 0 0)
			(layers "F.Cu" "F.Mask" "F.Paste")
			(net "RST_PCIE_CPU0_DEV_PERST_N")
		)
		(pad "2" smd circle
			(at 0.40005 0 180)
			(size 0 0)
			(layers "F.Cu" "F.Mask" "F.Paste")
			(net "RST_OCP_V3_1_N")
		)
	)
)
